# S9S_MB_2U (Grand Teton) — schematic netlist excerpt (pin names and nets, part order shuffled) for the footprints in the layout excerpt that follows; sources: Cadence DE-HDL packaged netlist, KiCad conversion of 03242023_DA0F0TMBIJ0_F0T_Motherboard_J_brd_V01_OCP.brd

C1181  Q_CAP  22UF 4V 20% X6S  pkg C0603  page 189 : A = P1V8_PCH_AUX ; B = GND
R1240  Q_RES  0 5% CHIP  pkg 0402LF  page 117 : A = H_CPU0_PM_FAST_WAKE_N ; B = H_CPU_PM_FAST_WAKE_N

(kicad_pcb
	(version 20260206)
	(generator "pcbnew")
	(generator_version "10.0")
	(general
		(thickness 1.6)
		(legacy_teardrops no)
	)
	(paper "A4")
	(title_block
		(title "03242023_DA0F0TMBIJ0_F0T_Motherboard_J_brd_V01_OCP.brd")
		(comment 1 "Grand Teton / footprints 4438-4439 of 6105")
	)
	(layers
		(0 "F.Cu" signal "TOP")
		(4 "In1.Cu" signal "GND")
		(6 "In2.Cu" signal "IN1")
		(8 "In3.Cu" signal "GND1")
		(10 "In4.Cu" signal "IN2")
		(12 "In5.Cu" signal "GND2")
		(14 "In6.Cu" signal "IN3")
		(16 "In7.Cu" signal "GND3")
		(18 "In8.Cu" signal "VCC")
		(20 "In9.Cu" signal "VCC1")
		(22 "In10.Cu" signal "GND4")
		(24 "In11.Cu" signal "IN4")
		(26 "In12.Cu" signal "GND5")
		(28 "In13.Cu" signal "IN5")
		(30 "In14.Cu" signal "GND6")
		(32 "In15.Cu" signal "IN6")
		(34 "In16.Cu" signal "GND7")
		(2 "B.Cu" signal "BOTTOM")
		(9 "F.Adhes" user "F.Adhesive")
		(11 "B.Adhes" user "B.Adhesive")
		(13 "F.Paste" user "Package Geometry/Pastemask Top")
		(15 "B.Paste" user "Package Geometry/Pastemask Bottom")
		(5 "F.SilkS" user "Ref Des/Silkscreen Top")
		(7 "B.SilkS" user "Ref Des/Silkscreen Bottom")
		(1 "F.Mask" user "Board Geometry/Soldermask Top")
		(3 "B.Mask" user "Board Geometry/Soldermask Bottom")
		(17 "Dwgs.User" user "User.Drawings")
		(19 "Cmts.User" user "User.Comments")
		(21 "Eco1.User" user "User.Eco1")
		(23 "Eco2.User" user "User.Eco2")
		(25 "Edge.Cuts" user "Board Geometry/Outline")
		(27 "Margin" user)
		(31 "F.CrtYd" user "Package Geometry/Place Bound Top")
		(29 "B.CrtYd" user "Package Geometry/Place Bound Bottom")
		(35 "F.Fab" user "Ref Des/Assembly Top")
		(33 "B.Fab" user "Ref Des/Assembly Bottom")
	)
	(footprint ""
		(layer "B.Cu")
		(at 332.197456 -58.473086 -90)
		(property "Reference" "C1181"
			(at 0 0 90)
			(layer "B.SilkS")
			(hide yes)
			(effects
				(font
					(size 1.27 1.27)
				)
				(justify mirror)
			)
		)
		(property "Value" ""
			(at 0 0 90)
			(layer "B.Fab")
			(effects
				(font
					(size 1.27 1.27)
				)
				(justify mirror)
			)
		)
		(duplicate_pad_numbers_are_jumpers no)
		(fp_line
			(start -1.2954 0.5842)
			(end 1.2954 0.5842)
			(stroke
				(width 0.1524)
				(type default)
			)
			(layer "B.SilkS")
		)
		(fp_line
			(start 1.2954 0.5842)
			(end 1.2954 -0.5842)
			(stroke
				(width 0.1524)
				(type default)
			)
			(layer "B.SilkS")
		)
		(fp_line
			(start -1.2954 -0.5842)
			(end -1.2954 0.5842)
			(stroke
				(width 0.1524)
				(type default)
			)
			(layer "B.SilkS")
		)
		(fp_line
			(start 0 -0.5842)
			(end 0 0.5842)
			(stroke
				(width 0.1524)
				(type default)
			)
			(layer "B.SilkS")
		)
		(fp_line
			(start 1.2954 -0.5842)
			(end -1.2954 -0.5842)
			(stroke
				(width 0.1524)
				(type default)
			)
			(layer "B.SilkS")
		)
		(fp_line
			(start -0.8636 0.4572)
			(end 0.8636 0.4572)
			(stroke
				(width 0.1)
				(type default)
			)
			(layer "B.Fab")
		)
		(fp_line
			(start 0.8636 0.4572)
			(end 0.8636 0.4064)
			(stroke
				(width 0.1)
				(type default)
			)
			(layer "B.Fab")
		)
		(fp_line
			(start -1.1938 0.4064)
			(end -0.8636 0.4064)
			(stroke
				(width 0.1)
				(type default)
			)
			(layer "B.Fab")
		)
		(fp_line
			(start -0.8636 0.4064)
			(end -0.8636 0.4572)
			(stroke
				(width 0.1)
				(type default)
			)
			(layer "B.Fab")
		)
		(fp_line
			(start 0.8636 0.4064)
			(end 1.1938 0.4064)
			(stroke
				(width 0.1)
				(type default)
			)
			(layer "B.Fab")
		)
		(fp_line
			(start 1.1938 0.4064)
			(end 1.1938 -0.4064)
			(stroke
				(width 0.1)
				(type default)
			)
			(layer "B.Fab")
		)
		(fp_line
			(start -1.1938 -0.4064)
			(end -1.1938 0.4064)
			(stroke
				(width 0.1)
				(type default)
			)
			(layer "B.Fab")
		)
		(fp_line
			(start -0.8636 -0.4064)
			(end -1.1938 -0.4064)
			(stroke
				(width 0.1)
				(type default)
			)
			(layer "B.Fab")
		)
		(fp_line
			(start 0.8636 -0.4064)
			(end 0.8636 -0.4572)
			(stroke
				(width 0.1)
				(type default)
			)
			(layer "B.Fab")
		)
		(fp_line
			(start 1.1938 -0.4064)
			(end 0.8636 -0.4064)
			(stroke
				(width 0.1)
				(type default)
			)
			(layer "B.Fab")
		)
		(fp_line
			(start -0.8636 -0.4572)
			(end -0.8636 -0.4064)
			(stroke
				(width 0.1)
				(type default)
			)
			(layer "B.Fab")
		)
		(fp_line
			(start 0.8636 -0.4572)
			(end -0.8636 -0.4572)
			(stroke
				(width 0.1)
				(type default)
			)
			(layer "B.Fab")
		)
		(pad "1" smd rect
			(at 0.7366 0 180)
			(size 0.7112 0.8128)
			(layers "B.Cu" "B.Mask" "B.Paste")
			(net "P1V8_PCH_AUX")
		)
		(pad "2" smd rect
			(at -0.7366 0 180)
			(size 0.7112 0.8128)
			(layers "B.Cu" "B.Mask" "B.Paste")
			(net "GND")
		)
	)
	(footprint ""
		(layer "B.Cu")
		(at 380.80823 -190.82131 90)
		(property "Reference" "R1240"
			(at 0 0 90)
			(layer "B.SilkS")
			(hide yes)
			(effects
				(font
					(size 1.27 1.27)
				)
				(justify mirror)
			)
		)
		(property "Value" ""
			(at 0 0 90)
			(layer "B.Fab")
			(effects
				(font
					(size 1.27 1.27)
				)
				(justify mirror)
			)
		)
		(duplicate_pad_numbers_are_jumpers no)
		(fp_line
			(start 0.7874 -0.4064)
			(end -0.7874 -0.4064)
			(stroke
				(width 0.1524)
				(type default)
			)
			(layer "B.SilkS")
		)
		(fp_line
			(start -0.7874 -0.4064)
			(end -0.7874 0.4064)
			(stroke
				(width 0.1524)
				(type default)
			)
			(layer "B.SilkS")
		)
		(fp_line
			(start 0.7874 0.4064)
			(end 0.7874 -0.4064)
			(stroke
				(width 0.1524)
				(type default)
			)
			(layer "B.SilkS")
		)
		(fp_line
			(start -0.7874 0.4064)
			(end 0.7874 0.4064)
			(stroke
				(width 0.1524)
				(type default)
			)
			(layer "B.SilkS")
		)
		(fp_line
			(start 0.67945 -0.305054)
			(end 0.12065 -0.305054)
			(stroke
				(width 0.1)
				(type default)
			)
			(layer "B.Fab")
		)
		(fp_line
			(start 0.12065 -0.305054)
			(end 0.12065 -0.2794)
			(stroke
				(width 0.1)
				(type default)
			)
			(layer "B.Fab")
		)
		(fp_line
			(start -0.12065 -0.3048)
			(end -0.67945 -0.3048)
			(stroke
				(width 0.1)
				(type default)
			)
			(layer "B.Fab")
		)
		(fp_line
			(start -0.67945 -0.3048)
			(end -0.67945 0.3048)
			(stroke
				(width 0.1)
				(type default)
			)
			(layer "B.Fab")
		)
		(fp_line
			(start 0.12065 -0.2794)
			(end -0.12065 -0.2794)
			(stroke
				(width 0.1)
				(type default)
			)
			(layer "B.Fab")
		)
		(fp_line
			(start -0.12065 -0.2794)
			(end -0.12065 -0.3048)
			(stroke
				(width 0.1)
				(type default)
			)
			(layer "B.Fab")
		)
		(fp_line
			(start 0.12065 0.2794)
			(end 0.12065 0.3048)
			(stroke
				(width 0.1)
				(type default)
			)
			(layer "B.Fab")
		)
		(fp_line
			(start -0.120396 0.2794)
			(end 0.12065 0.2794)
			(stroke
				(width 0.1)
				(type default)
			)
			(layer "B.Fab")
		)
		(fp_line
			(start 0.67945 0.3048)
			(end 0.67945 -0.305054)
			(stroke
				(width 0.1)
				(type default)
			)
			(layer "B.Fab")
		)
		(fp_line
			(start 0.12065 0.3048)
			(end 0.67945 0.3048)
			(stroke
				(width 0.1)
				(type default)
			)
			(layer "B.Fab")
		)
		(fp_line
			(start -0.120396 0.3048)
			(end -0.120396 0.2794)
			(stroke
				(width 0.1)
				(type default)
			)
			(layer "B.Fab")
		)
		(fp_line
			(start -0.67945 0.3048)
			(end -0.120396 0.3048)
			(stroke
				(width 0.1)
				(type default)
			)
			(layer "B.Fab")
		)
		(pad "1" smd circle
			(at 0.40005 0 270)
			(size 0 0)
			(layers "B.Cu" "B.Mask" "B.Paste")
			(net "H_CPU0_PM_FAST_WAKE_N")
		)
		(pad "2" smd circle
			(at -0.40005 0 270)
			(size 0 0)
			(layers "B.Cu" "B.Mask" "B.Paste")
			(net "H_CPU_PM_FAST_WAKE_N")
		)
	)
)
